# T6G (Grand Teton) — schematic netlist excerpt (pin names and nets, part order shuffled) for the footprints in the layout excerpt that follows; sources: Cadence DE-HDL packaged netlist, KiCad conversion of 04192023_DAF0TMB3IC0_F0TG_MB_C_brd_V02_OCP.brd

R1635  Q_RES  22 1% CHIP  pkg 0402LF  page 172 : A = JTAG_TRST_R_N ; B = JTAG_TRST_N
R3397  Q_RES  33.2 1% CHIP  pkg 0402LF  page 129 : A = GPU_NVS_PWR_BRAKE_N_R ; B = GPU_NVS_PWR_BRAKE_N_BUF

(kicad_pcb
	(version 20260206)
	(generator "pcbnew")
	(generator_version "10.0")
	(general
		(thickness 1.6)
		(legacy_teardrops no)
	)
	(paper "A4")
	(title_block
		(title "04192023_DAF0TMB3IC0_F0TG_MB_C_brd_V02_OCP.brd")
		(comment 1 "Grand Teton / footprints 3378-3379 of 8354")
	)
	(layers
		(0 "F.Cu" signal "TOP")
		(4 "In1.Cu" signal "GND")
		(6 "In2.Cu" signal "IN1")
		(8 "In3.Cu" signal "GND1")
		(10 "In4.Cu" signal "IN2")
		(12 "In5.Cu" signal "GND2")
		(14 "In6.Cu" signal "IN3")
		(16 "In7.Cu" signal "GND3")
		(18 "In8.Cu" signal "VCC")
		(20 "In9.Cu" signal "VCC1")
		(22 "In10.Cu" signal "GND4")
		(24 "In11.Cu" signal "IN4")
		(26 "In12.Cu" signal "GND5")
		(28 "In13.Cu" signal "IN5")
		(30 "In14.Cu" signal "GND6")
		(32 "In15.Cu" signal "IN6")
		(34 "In16.Cu" signal "GND7")
		(2 "B.Cu" signal "BOTTOM")
		(9 "F.Adhes" user "F.Adhesive")
		(11 "B.Adhes" user "B.Adhesive")
		(13 "F.Paste" user "Package Geometry/Pastemask Top")
		(15 "B.Paste" user "Package Geometry/Pastemask Bottom")
		(5 "F.SilkS" user "Ref Des/Silkscreen Top")
		(7 "B.SilkS" user "Ref Des/Silkscreen Bottom")
		(1 "F.Mask" user "Board Geometry/Soldermask Top")
		(3 "B.Mask" user "Board Geometry/Soldermask Bottom")
		(17 "Dwgs.User" user "User.Drawings")
		(19 "Cmts.User" user "User.Comments")
		(21 "Eco1.User" user "User.Eco1")
		(23 "Eco2.User" user "User.Eco2")
		(25 "Edge.Cuts" user "Board Geometry/Outline")
		(27 "Margin" user)
		(31 "F.CrtYd" user "Package Geometry/Place Bound Top")
		(29 "B.CrtYd" user "Package Geometry/Place Bound Bottom")
		(35 "F.Fab" user "Ref Des/Assembly Top")
		(33 "B.Fab" user "Ref Des/Assembly Bottom")
	)
	(footprint ""
		(layer "F.Cu")
		(at 105.537 -418.973 180)
		(property "Reference" "R3397"
			(at 0 0 180)
			(layer "F.SilkS")
			(hide yes)
			(effects
				(font
					(size 1.27 1.27)
				)
			)
		)
		(property "Value" ""
			(at 0 0 180)
			(layer "F.Fab")
			(effects
				(font
					(size 1.27 1.27)
				)
			)
		)
		(duplicate_pad_numbers_are_jumpers no)
		(fp_line
			(start 0.7874 0.4064)
			(end -0.7874 0.4064)
			(stroke
				(width 0.1524)
				(type default)
			)
			(layer "F.SilkS")
		)
		(fp_line
			(start 0.7874 -0.4064)
			(end 0.7874 0.4064)
			(stroke
				(width 0.1524)
				(type default)
			)
			(layer "F.SilkS")
		)
		(fp_line
			(start -0.7874 0.4064)
			(end -0.7874 -0.4064)
			(stroke
				(width 0.1524)
				(type default)
			)
			(layer "F.SilkS")
		)
		(fp_line
			(start -0.7874 -0.4064)
			(end 0.7874 -0.4064)
			(stroke
				(width 0.1524)
				(type default)
			)
			(layer "F.SilkS")
		)
		(fp_line
			(start 0.67945 0.3048)
			(end 0.120396 0.3048)
			(stroke
				(width 0.1)
				(type default)
			)
			(layer "F.Fab")
		)
		(fp_line
			(start 0.67945 -0.3048)
			(end 0.67945 0.3048)
			(stroke
				(width 0.1)
				(type default)
			)
			(layer "F.Fab")
		)
		(fp_line
			(start 0.12065 -0.2794)
			(end 0.12065 -0.3048)
			(stroke
				(width 0.1)
				(type default)
			)
			(layer "F.Fab")
		)
		(fp_line
			(start 0.12065 -0.3048)
			(end 0.67945 -0.3048)
			(stroke
				(width 0.1)
				(type default)
			)
			(layer "F.Fab")
		)
		(fp_line
			(start 0.120396 0.3048)
			(end 0.120396 0.2794)
			(stroke
				(width 0.1)
				(type default)
			)
			(layer "F.Fab")
		)
		(fp_line
			(start 0.120396 0.2794)
			(end -0.12065 0.2794)
			(stroke
				(width 0.1)
				(type default)
			)
			(layer "F.Fab")
		)
		(fp_line
			(start -0.12065 0.3048)
			(end -0.67945 0.3048)
			(stroke
				(width 0.1)
				(type default)
			)
			(layer "F.Fab")
		)
		(fp_line
			(start -0.12065 0.2794)
			(end -0.12065 0.3048)
			(stroke
				(width 0.1)
				(type default)
			)
			(layer "F.Fab")
		)
		(fp_line
			(start -0.12065 -0.2794)
			(end 0.12065 -0.2794)
			(stroke
				(width 0.1)
				(type default)
			)
			(layer "F.Fab")
		)
		(fp_line
			(start -0.12065 -0.305054)
			(end -0.12065 -0.2794)
			(stroke
				(width 0.1)
				(type default)
			)
			(layer "F.Fab")
		)
		(fp_line
			(start -0.67945 0.3048)
			(end -0.67945 -0.305054)
			(stroke
				(width 0.1)
				(type default)
			)
			(layer "F.Fab")
		)
		(fp_line
			(start -0.67945 -0.305054)
			(end -0.12065 -0.305054)
			(stroke
				(width 0.1)
				(type default)
			)
			(layer "F.Fab")
		)
		(pad "1" smd circle
			(at -0.40005 0 180)
			(size 0 0)
			(layers "F.Cu" "F.Mask" "F.Paste")
			(net "GPU_NVS_PWR_BRAKE_N_R")
		)
		(pad "2" smd circle
			(at 0.40005 0 180)
			(size 0 0)
			(layers "F.Cu" "F.Mask" "F.Paste")
			(net "GPU_NVS_PWR_BRAKE_N_BUF")
		)
	)
	(footprint ""
		(layer "F.Cu")
		(at 259.834126 -98.746056 180)
		(property "Reference" "R1635"
			(at 0 0 180)
			(layer "F.SilkS")
			(hide yes)
			(effects
				(font
					(size 1.27 1.27)
				)
			)
		)
		(property "Value" ""
			(at 0 0 180)
			(layer "F.Fab")
			(effects
				(font
					(size 1.27 1.27)
				)
			)
		)
		(duplicate_pad_numbers_are_jumpers no)
		(fp_line
			(start 0.7874 0.4064)
			(end -0.7874 0.4064)
			(stroke
				(width 0.1524)
				(type default)
			)
			(layer "F.SilkS")
		)
		(fp_line
			(start 0.7874 -0.4064)
			(end 0.7874 0.4064)
			(stroke
				(width 0.1524)
				(type default)
			)
			(layer "F.SilkS")
		)
		(fp_line
			(start -0.7874 0.4064)
			(end -0.7874 -0.4064)
			(stroke
				(width 0.1524)
				(type default)
			)
			(layer "F.SilkS")
		)
		(fp_line
			(start -0.7874 -0.4064)
			(end 0.7874 -0.4064)
			(stroke
				(width 0.1524)
				(type default)
			)
			(layer "F.SilkS")
		)
		(fp_line
			(start 0.67945 0.3048)
			(end 0.120396 0.3048)
			(stroke
				(width 0.1)
				(type default)
			)
			(layer "F.Fab")
		)
		(fp_line
			(start 0.67945 -0.3048)
			(end 0.67945 0.3048)
			(stroke
				(width 0.1)
				(type default)
			)
			(layer "F.Fab")
		)
		(fp_line
			(start 0.12065 -0.2794)
			(end 0.12065 -0.3048)
			(stroke
				(width 0.1)
				(type default)
			)
			(layer "F.Fab")
		)
		(fp_line
			(start 0.12065 -0.3048)
			(end 0.67945 -0.3048)
			(stroke
				(width 0.1)
				(type default)
			)
			(layer "F.Fab")
		)
		(fp_line
			(start 0.120396 0.3048)
			(end 0.120396 0.2794)
			(stroke
				(width 0.1)
				(type default)
			)
			(layer "F.Fab")
		)
		(fp_line
			(start 0.120396 0.2794)
			(end -0.12065 0.2794)
			(stroke
				(width 0.1)
				(type default)
			)
			(layer "F.Fab")
		)
		(fp_line
			(start -0.12065 0.3048)
			(end -0.67945 0.3048)
			(stroke
				(width 0.1)
				(type default)
			)
			(layer "F.Fab")
		)
		(fp_line
			(start -0.12065 0.2794)
			(end -0.12065 0.3048)
			(stroke
				(width 0.1)
				(type default)
			)
			(layer "F.Fab")
		)
		(fp_line
			(start -0.12065 -0.2794)
			(end 0.12065 -0.2794)
			(stroke
				(width 0.1)
				(type default)
			)
			(layer "F.Fab")
		)
		(fp_line
			(start -0.12065 -0.305054)
			(end -0.12065 -0.2794)
			(stroke
				(width 0.1)
				(type default)
			)
			(layer "F.Fab")
		)
		(fp_line
			(start -0.67945 0.3048)
			(end -0.67945 -0.305054)
			(stroke
				(width 0.1)
				(type default)
			)
			(layer "F.Fab")
		)
		(fp_line
			(start -0.67945 -0.305054)
			(end -0.12065 -0.305054)
			(stroke
				(width 0.1)
				(type default)
			)
			(layer "F.Fab")
		)
		(pad "1" smd circle
			(at -0.40005 0 180)
			(size 0 0)
			(layers "F.Cu" "F.Mask" "F.Paste")
			(net "JTAG_TRST_R_N")
		)
		(pad "2" smd circle
			(at 0.40005 0 180)
			(size 0 0)
			(layers "F.Cu" "F.Mask" "F.Paste")
			(net "JTAG_TRST_N")
		)
	)
)
